# T6G (Grand Teton) — schematic netlist excerpt (pin names and nets, part order shuffled) for the footprints in the layout excerpt that follows; sources: Cadence DE-HDL packaged netlist, KiCad conversion of 04192023_DAF0TMB3IC0_F0TG_MB_C_brd_V02_OCP.brd

R250  Q_RES  0 5% CHIP  pkg 0402LF  page 81 : A = FM_CPU0_SMERR_N ; B = CPU0_SMERR_N
R280  Q_RES  0 5% CHIP  pkg 0402LF  page 81 : A = PWRGD_PVDD11_S3_P1 ; B = FM_PWRGD_PVDD11_S3_P1

(kicad_pcb
	(version 20260206)
	(generator "pcbnew")
	(generator_version "10.0")
	(general
		(thickness 1.6)
		(legacy_teardrops no)
	)
	(paper "A4")
	(title_block
		(title "04192023_DAF0TMB3IC0_F0TG_MB_C_brd_V02_OCP.brd")
		(comment 1 "Grand Teton / footprints 3517-3518 of 8354")
	)
	(layers
		(0 "F.Cu" signal "TOP")
		(4 "In1.Cu" signal "GND")
		(6 "In2.Cu" signal "IN1")
		(8 "In3.Cu" signal "GND1")
		(10 "In4.Cu" signal "IN2")
		(12 "In5.Cu" signal "GND2")
		(14 "In6.Cu" signal "IN3")
		(16 "In7.Cu" signal "GND3")
		(18 "In8.Cu" signal "VCC")
		(20 "In9.Cu" signal "VCC1")
		(22 "In10.Cu" signal "GND4")
		(24 "In11.Cu" signal "IN4")
		(26 "In12.Cu" signal "GND5")
		(28 "In13.Cu" signal "IN5")
		(30 "In14.Cu" signal "GND6")
		(32 "In15.Cu" signal "IN6")
		(34 "In16.Cu" signal "GND7")
		(2 "B.Cu" signal "BOTTOM")
		(9 "F.Adhes" user "F.Adhesive")
		(11 "B.Adhes" user "B.Adhesive")
		(13 "F.Paste" user "Package Geometry/Pastemask Top")
		(15 "B.Paste" user "Package Geometry/Pastemask Bottom")
		(5 "F.SilkS" user "Ref Des/Silkscreen Top")
		(7 "B.SilkS" user "Ref Des/Silkscreen Bottom")
		(1 "F.Mask" user "Board Geometry/Soldermask Top")
		(3 "B.Mask" user "Board Geometry/Soldermask Bottom")
		(17 "Dwgs.User" user "User.Drawings")
		(19 "Cmts.User" user "User.Comments")
		(21 "Eco1.User" user "User.Eco1")
		(23 "Eco2.User" user "User.Eco2")
		(25 "Edge.Cuts" user "Board Geometry/Outline")
		(27 "Margin" user)
		(31 "F.CrtYd" user "Package Geometry/Place Bound Top")
		(29 "B.CrtYd" user "Package Geometry/Place Bound Bottom")
		(35 "F.Fab" user "Ref Des/Assembly Top")
		(33 "B.Fab" user "Ref Des/Assembly Bottom")
	)
	(footprint ""
		(layer "F.Cu")
		(at 197.269608 -109.561376 180)
		(property "Reference" "R280"
			(at 0 0 180)
			(layer "F.SilkS")
			(hide yes)
			(effects
				(font
					(size 1.27 1.27)
				)
			)
		)
		(property "Value" ""
			(at 0 0 180)
			(layer "F.Fab")
			(effects
				(font
					(size 1.27 1.27)
				)
			)
		)
		(duplicate_pad_numbers_are_jumpers no)
		(fp_line
			(start 0.7874 0.4064)
			(end -0.7874 0.4064)
			(stroke
				(width 0.1524)
				(type default)
			)
			(layer "F.SilkS")
		)
		(fp_line
			(start 0.7874 -0.4064)
			(end 0.7874 0.4064)
			(stroke
				(width 0.1524)
				(type default)
			)
			(layer "F.SilkS")
		)
		(fp_line
			(start -0.7874 0.4064)
			(end -0.7874 -0.4064)
			(stroke
				(width 0.1524)
				(type default)
			)
			(layer "F.SilkS")
		)
		(fp_line
			(start -0.7874 -0.4064)
			(end 0.7874 -0.4064)
			(stroke
				(width 0.1524)
				(type default)
			)
			(layer "F.SilkS")
		)
		(fp_line
			(start 0.67945 0.3048)
			(end 0.120396 0.3048)
			(stroke
				(width 0.1)
				(type default)
			)
			(layer "F.Fab")
		)
		(fp_line
			(start 0.67945 -0.3048)
			(end 0.67945 0.3048)
			(stroke
				(width 0.1)
				(type default)
			)
			(layer "F.Fab")
		)
		(fp_line
			(start 0.12065 -0.2794)
			(end 0.12065 -0.3048)
			(stroke
				(width 0.1)
				(type default)
			)
			(layer "F.Fab")
		)
		(fp_line
			(start 0.12065 -0.3048)
			(end 0.67945 -0.3048)
			(stroke
				(width 0.1)
				(type default)
			)
			(layer "F.Fab")
		)
		(fp_line
			(start 0.120396 0.3048)
			(end 0.120396 0.2794)
			(stroke
				(width 0.1)
				(type default)
			)
			(layer "F.Fab")
		)
		(fp_line
			(start 0.120396 0.2794)
			(end -0.12065 0.2794)
			(stroke
				(width 0.1)
				(type default)
			)
			(layer "F.Fab")
		)
		(fp_line
			(start -0.12065 0.3048)
			(end -0.67945 0.3048)
			(stroke
				(width 0.1)
				(type default)
			)
			(layer "F.Fab")
		)
		(fp_line
			(start -0.12065 0.2794)
			(end -0.12065 0.3048)
			(stroke
				(width 0.1)
				(type default)
			)
			(layer "F.Fab")
		)
		(fp_line
			(start -0.12065 -0.2794)
			(end 0.12065 -0.2794)
			(stroke
				(width 0.1)
				(type default)
			)
			(layer "F.Fab")
		)
		(fp_line
			(start -0.12065 -0.305054)
			(end -0.12065 -0.2794)
			(stroke
				(width 0.1)
				(type default)
			)
			(layer "F.Fab")
		)
		(fp_line
			(start -0.67945 0.3048)
			(end -0.67945 -0.305054)
			(stroke
				(width 0.1)
				(type default)
			)
			(layer "F.Fab")
		)
		(fp_line
			(start -0.67945 -0.305054)
			(end -0.12065 -0.305054)
			(stroke
				(width 0.1)
				(type default)
			)
			(layer "F.Fab")
		)
		(pad "1" smd circle
			(at -0.40005 0 180)
			(size 0 0)
			(layers "F.Cu" "F.Mask" "F.Paste")
			(net "PWRGD_PVDD11_S3_P1")
		)
		(pad "2" smd circle
			(at 0.40005 0 180)
			(size 0 0)
			(layers "F.Cu" "F.Mask" "F.Paste")
			(net "FM_PWRGD_PVDD11_S3_P1")
		)
	)
	(footprint ""
		(layer "F.Cu")
		(at 186.055 -129.377948 90)
		(property "Reference" "R250"
			(at 0 0 90)
			(layer "F.SilkS")
			(hide yes)
			(effects
				(font
					(size 1.27 1.27)
				)
			)
		)
		(property "Value" ""
			(at 0 0 90)
			(layer "F.Fab")
			(effects
				(font
					(size 1.27 1.27)
				)
			)
		)
		(duplicate_pad_numbers_are_jumpers no)
		(fp_line
			(start 0.7874 -0.4064)
			(end 0.7874 0.4064)
			(stroke
				(width 0.1524)
				(type default)
			)
			(layer "F.SilkS")
		)
		(fp_line
			(start -0.7874 -0.4064)
			(end 0.7874 -0.4064)
			(stroke
				(width 0.1524)
				(type default)
			)
			(layer "F.SilkS")
		)
		(fp_line
			(start 0.7874 0.4064)
			(end -0.7874 0.4064)
			(stroke
				(width 0.1524)
				(type default)
			)
			(layer "F.SilkS")
		)
		(fp_line
			(start -0.7874 0.4064)
			(end -0.7874 -0.4064)
			(stroke
				(width 0.1524)
				(type default)
			)
			(layer "F.SilkS")
		)
		(fp_line
			(start -0.12065 -0.305054)
			(end -0.12065 -0.2794)
			(stroke
				(width 0.1)
				(type default)
			)
			(layer "F.Fab")
		)
		(fp_line
			(start -0.67945 -0.305054)
			(end -0.12065 -0.305054)
			(stroke
				(width 0.1)
				(type default)
			)
			(layer "F.Fab")
		)
		(fp_line
			(start 0.67945 -0.3048)
			(end 0.67945 0.3048)
			(stroke
				(width 0.1)
				(type default)
			)
			(layer "F.Fab")
		)
		(fp_line
			(start 0.12065 -0.3048)
			(end 0.67945 -0.3048)
			(stroke
				(width 0.1)
				(type default)
			)
			(layer "F.Fab")
		)
		(fp_line
			(start 0.12065 -0.2794)
			(end 0.12065 -0.3048)
			(stroke
				(width 0.1)
				(type default)
			)
			(layer "F.Fab")
		)
		(fp_line
			(start -0.12065 -0.2794)
			(end 0.12065 -0.2794)
			(stroke
				(width 0.1)
				(type default)
			)
			(layer "F.Fab")
		)
		(fp_line
			(start 0.120396 0.2794)
			(end -0.12065 0.2794)
			(stroke
				(width 0.1)
				(type default)
			)
			(layer "F.Fab")
		)
		(fp_line
			(start -0.12065 0.2794)
			(end -0.12065 0.3048)
			(stroke
				(width 0.1)
				(type default)
			)
			(layer "F.Fab")
		)
		(fp_line
			(start 0.67945 0.3048)
			(end 0.120396 0.3048)
			(stroke
				(width 0.1)
				(type default)
			)
			(layer "F.Fab")
		)
		(fp_line
			(start 0.120396 0.3048)
			(end 0.120396 0.2794)
			(stroke
				(width 0.1)
				(type default)
			)
			(layer "F.Fab")
		)
		(fp_line
			(start -0.12065 0.3048)
			(end -0.67945 0.3048)
			(stroke
				(width 0.1)
				(type default)
			)
			(layer "F.Fab")
		)
		(fp_line
			(start -0.67945 0.3048)
			(end -0.67945 -0.305054)
			(stroke
				(width 0.1)
				(type default)
			)
			(layer "F.Fab")
		)
		(pad "1" smd circle
			(at -0.40005 0 90)
			(size 0 0)
			(layers "F.Cu" "F.Mask" "F.Paste")
			(net "FM_CPU0_SMERR_N")
		)
		(pad "2" smd circle
			(at 0.40005 0 90)
			(size 0 0)
			(layers "F.Cu" "F.Mask" "F.Paste")
			(net "CPU0_SMERR_N")
		)
	)
)
